(kicad_pcb
	(version 20241229)
	(generator "pcbnew")
	(generator_version "9.0")
	(general
		(thickness 1.63)
		(legacy_teardrops no)
	)
	(paper "A4")
	(title_block
		(title "CM4 Baseboard")
		(date "2026-01-05")
		(rev "1.1.1")
		(company "Antmicro Ltd")
		(comment 1 "www.antmicro.com")
		(comment 9 "footprints 497-501 of 506")
	)
	(layers
		(0 "F.Cu" signal)
		(4 "In1.Cu" power)
		(6 "In2.Cu" power)
		(8 "In3.Cu" signal)
		(10 "In4.Cu" signal)
		(2 "B.Cu" signal)
		(9 "F.Adhes" user "F.Adhesive")
		(11 "B.Adhes" user "B.Adhesive")
		(13 "F.Paste" user)
		(15 "B.Paste" user)
		(5 "F.SilkS" user "F.Silkscreen")
		(7 "B.SilkS" user "B.Silkscreen")
		(1 "F.Mask" user)
		(3 "B.Mask" user)
		(17 "Dwgs.User" user "User.Drawings")
		(19 "Cmts.User" user "User.Comments")
		(21 "Eco1.User" user "User.Eco1")
		(23 "Eco2.User" user "User.Eco2")
		(25 "Edge.Cuts" user)
		(27 "Margin" user)
		(31 "F.CrtYd" user "F.Courtyard")
		(29 "B.CrtYd" user "B.Courtyard")
		(35 "F.Fab" user)
		(33 "B.Fab" user)
	)
	(footprint "antmicro-footprints:C_0402_1005Metric"
		(layer "B.Cu")
		(at 99.417962 176.9665 90)
		(descr "Capacitor SMD 0402")
		(tags "capacitor SMD 0402")
		(property "Reference" "C701"
			(at -2.76 2.33 90)
			(layer "B.SilkS")
			(effects
				(font
					(size 0.7 0.7)
					(thickness 0.15)
				)
				(justify right bottom mirror)
			)
		)
		(property "Value" "C_10u_0402"
			(at -1.022927 -2.155213 90)
			(layer "B.Fab")
			(effects
				(font
					(size 0.7 0.7)
					(thickness 0.15)
				)
				(justify right bottom mirror)
			)
		)
		(property "Datasheet" "https://www.yageo.com/en/Chart/Download/pdf/CC0402MRX5R5BB106"
			(at 0 0 90)
			(layer "B.Fab")
			(hide yes)
			(effects
				(font
					(size 1.27 1.27)
					(thickness 0.15)
				)
			)
		)
		(property "MPN" "CC0402MRX5R5BB106"
			(at 0 0 90)
			(unlocked yes)
			(layer "B.Fab")
			(hide yes)
			(effects
				(font
					(size 1 1)
					(thickness 0.15)
				)
				(justify mirror)
			)
		)
		(property "Manufacturer" "YAGEO"
			(at 0 0 90)
			(unlocked yes)
			(layer "B.Fab")
			(hide yes)
			(effects
				(font
					(size 1 1)
					(thickness 0.15)
				)
				(justify mirror)
			)
		)
		(property "License" "Apache-2.0"
			(at 0 0 90)
			(unlocked yes)
			(layer "B.Fab")
			(hide yes)
			(effects
				(font
					(size 1 1)
					(thickness 0.15)
				)
				(justify mirror)
			)
		)
		(property "Author" "Antmicro"
			(at 0 0 90)
			(unlocked yes)
			(layer "B.Fab")
			(hide yes)
			(effects
				(font
					(size 1 1)
					(thickness 0.15)
				)
				(justify mirror)
			)
		)
		(property "Val" "10u"
			(at 0 0 90)
			(unlocked yes)
			(layer "B.Fab")
			(hide yes)
			(effects
				(font
					(size 1 1)
					(thickness 0.15)
				)
				(justify mirror)
			)
		)
		(property "Voltage" ""
			(at 0 0 90)
			(unlocked yes)
			(layer "B.Fab")
			(hide yes)
			(effects
				(font
					(size 1 1)
					(thickness 0.15)
				)
				(justify mirror)
			)
		)
		(property "Dielectric" ""
			(at 0 0 90)
			(unlocked yes)
			(layer "B.Fab")
			(hide yes)
			(effects
				(font
					(size 1 1)
					(thickness 0.15)
				)
				(justify mirror)
			)
		)
		(sheetname "/Display/")
		(sheetfile "display.kicad_sch")
		(attr smd)
		(fp_rect
			(start -0.925 0.47)
			(end 0.925 -0.47)
			(stroke
				(width 0.05)
				(type default)
			)
			(fill no)
			(layer "B.CrtYd")
		)
		(fp_line
			(start 0.504 -0.248)
			(end -0.494 -0.248)
			(stroke
				(width 0.15)
				(type solid)
			)
			(layer "B.Fab")
		)
		(fp_line
			(start -0.494 -0.248)
			(end -0.494 0.25)
			(stroke
				(width 0.15)
				(type solid)
			)
			(layer "B.Fab")
		)
		(fp_line
			(start 0.504 0.25)
			(end 0.504 -0.248)
			(stroke
				(width 0.15)
				(type solid)
			)
			(layer "B.Fab")
		)
		(fp_line
			(start -0.494 0.25)
			(end 0.504 0.25)
			(stroke
				(width 0.15)
				(type solid)
			)
			(layer "B.Fab")
		)
		(fp_text user "${REFERENCE}"
			(at -0.939 -4.599 270)
			(layer "B.Fab")
			(effects
				(font
					(size 0.7 0.7)
					(thickness 0.15)
				)
				(justify left bottom mirror)
			)
		)
		(fp_text user "Author: Antmicro"
			(at -0.939 -3.399 270)
			(layer "B.Fab")
			(effects
				(font
					(size 0.7 0.7)
					(thickness 0.15)
				)
				(justify left bottom mirror)
			)
		)
		(fp_text user "License: Apache-2.0"
			(at -0.939 -5.799 270)
			(layer "B.Fab")
			(effects
				(font
					(size 0.7 0.7)
					(thickness 0.15)
				)
				(justify left bottom mirror)
			)
		)
		(pad "1" smd roundrect
			(at -0.48 0 90)
			(size 0.59 0.64)
			(layers "B.Cu" "B.Mask" "B.Paste")
			(roundrect_rratio 0.25)
			(net 3 "GND")
			(pintype "passive")
		)
		(pad "2" smd roundrect
			(at 0.48 0 90)
			(size 0.59 0.64)
			(layers "B.Cu" "B.Mask" "B.Paste")
			(roundrect_rratio 0.25)
			(net 464 "Net-(D709-C)")
			(pintype "passive")
		)
	)
	(footprint "antmicro-footprints:R_0402_1005Metric"
		(layer "B.Cu")
		(at 86 116.95 -90)
		(descr "Resistor SMD 0402")
		(tags "resistor SMD 0402")
		(property "Reference" "R933"
			(at -3.78 -0.4 90)
			(layer "B.SilkS")
			(effects
				(font
					(size 0.7 0.7)
					(thickness 0.15)
				)
				(justify left bottom mirror)
			)
		)
		(property "Value" "R_10k_0402"
			(at -1.011843 -1.772047 90)
			(layer "B.Fab")
			(effects
				(font
					(size 0.7 0.7)
					(thickness 0.15)
				)
				(justify left bottom mirror)
			)
		)
		(property "Datasheet" "https://www.bourns.com/docs/product-datasheets/cr.pdf"
			(at 0 0 270)
			(layer "B.Fab")
			(hide yes)
			(effects
				(font
					(size 1.27 1.27)
					(thickness 0.15)
				)
			)
		)
		(property "Manufacturer" "Bourns"
			(at 0 0 270)
			(unlocked yes)
			(layer "B.Fab")
			(hide yes)
			(effects
				(font
					(size 1 1)
					(thickness 0.15)
				)
				(justify mirror)
			)
		)
		(property "MPN" "CR0402-FX-1002GLF"
			(at 0 0 270)
			(unlocked yes)
			(layer "B.Fab")
			(hide yes)
			(effects
				(font
					(size 1 1)
					(thickness 0.15)
				)
				(justify mirror)
			)
		)
		(property "Val" "10k"
			(at 0 0 270)
			(unlocked yes)
			(layer "B.Fab")
			(hide yes)
			(effects
				(font
					(size 1 1)
					(thickness 0.15)
				)
				(justify mirror)
			)
		)
		(property "License" "Apache-2.0"
			(at 0 0 270)
			(unlocked yes)
			(layer "B.Fab")
			(hide yes)
			(effects
				(font
					(size 1 1)
					(thickness 0.15)
				)
				(justify mirror)
			)
		)
		(property "Author" "Antmicro"
			(at 0 0 270)
			(unlocked yes)
			(layer "B.Fab")
			(hide yes)
			(effects
				(font
					(size 1 1)
					(thickness 0.15)
				)
				(justify mirror)
			)
		)
		(property "Tolerance" "1%"
			(at 0 0 270)
			(unlocked yes)
			(layer "B.Fab")
			(hide yes)
			(effects
				(font
					(size 1 1)
					(thickness 0.15)
				)
				(justify mirror)
			)
		)
		(sheetname "/USB/")
		(sheetfile "usb.kicad_sch")
		(attr smd)
		(fp_rect
			(start -0.925 0.47)
			(end 0.925 -0.47)
			(stroke
				(width 0.05)
				(type default)
			)
			(fill no)
			(layer "B.CrtYd")
		)
		(fp_rect
			(start -0.5 0.25)
			(end 0.5 -0.25)
			(stroke
				(width 0.15)
				(type solid)
			)
			(fill no)
			(layer "B.Fab")
		)
		(fp_text user "Author: Antmicro"
			(at -0.95 -4.169 90)
			(layer "B.Fab")
			(effects
				(font
					(size 0.7 0.7)
					(thickness 0.15)
				)
				(justify left bottom mirror)
			)
		)
		(fp_text user "${REFERENCE}"
			(at -0.95 -3.168 90)
			(layer "B.Fab")
			(effects
				(font
					(size 0.7 0.7)
					(thickness 0.15)
				)
				(justify left bottom mirror)
			)
		)
		(fp_text user "License: Apache-2.0"
			(at -0.95 -5.169 90)
			(layer "B.Fab")
			(effects
				(font
					(size 0.7 0.7)
					(thickness 0.15)
				)
				(justify left bottom mirror)
			)
		)
		(pad "1" smd roundrect
			(at -0.48 0 270)
			(size 0.59 0.64)
			(layers "B.Cu" "B.Mask" "B.Paste")
			(roundrect_rratio 0.25)
			(net 26 "/USB/USBD_VBUS")
			(pintype "passive")
		)
		(pad "2" smd roundrect
			(at 0.48 0 270)
			(size 0.59 0.64)
			(layers "B.Cu" "B.Mask" "B.Paste")
			(roundrect_rratio 0.25)
			(net 499 "Net-(Q906-G)")
			(pintype "passive")
		)
	)
	(footprint "antmicro-footprints:R_0402_1005Metric"
		(layer "B.Cu")
		(at 79.667962 146.4915 -90)
		(descr "Resistor SMD 0402")
		(tags "resistor SMD 0402")
		(property "Reference" "R412"
			(at -3.795 -0.42 90)
			(layer "B.SilkS")
			(effects
				(font
					(size 0.7 0.7)
					(thickness 0.15)
				)
				(justify left bottom mirror)
			)
		)
		(property "Value" "R_200R_0402"
			(at -1.011843 -1.772047 90)
			(layer "B.Fab")
			(effects
				(font
					(size 0.7 0.7)
					(thickness 0.15)
				)
				(justify left bottom mirror)
			)
		)
		(property "Datasheet" "https://www.bourns.com/docs/product-datasheets/cr.pdf"
			(at 0 0 270)
			(layer "B.Fab")
			(hide yes)
			(effects
				(font
					(size 1.27 1.27)
					(thickness 0.15)
				)
			)
		)
		(property "Manufacturer" "Bourns"
			(at 0 0 270)
			(unlocked yes)
			(layer "B.Fab")
			(hide yes)
			(effects
				(font
					(size 1 1)
					(thickness 0.15)
				)
				(justify mirror)
			)
		)
		(property "MPN" "CR0402-FX-2000GLF"
			(at 0 0 270)
			(unlocked yes)
			(layer "B.Fab")
			(hide yes)
			(effects
				(font
					(size 1 1)
					(thickness 0.15)
				)
				(justify mirror)
			)
		)
		(property "Val" "200R"
			(at 0 0 270)
			(unlocked yes)
			(layer "B.Fab")
			(hide yes)
			(effects
				(font
					(size 1 1)
					(thickness 0.15)
				)
				(justify mirror)
			)
		)
		(property "License" "Apache-2.0"
			(at 0 0 270)
			(unlocked yes)
			(layer "B.Fab")
			(hide yes)
			(effects
				(font
					(size 1 1)
					(thickness 0.15)
				)
				(justify mirror)
			)
		)
		(property "Author" "Antmicro"
			(at 0 0 270)
			(unlocked yes)
			(layer "B.Fab")
			(hide yes)
			(effects
				(font
					(size 1 1)
					(thickness 0.15)
				)
				(justify mirror)
			)
		)
		(property "Tolerance" "1%"
			(at 0 0 270)
			(unlocked yes)
			(layer "B.Fab")
			(hide yes)
			(effects
				(font
					(size 1 1)
					(thickness 0.15)
				)
				(justify mirror)
			)
		)
		(sheetname "/Ethernet/")
		(sheetfile "ethernet.kicad_sch")
		(attr smd)
		(fp_rect
			(start -0.925 0.47)
			(end 0.925 -0.47)
			(stroke
				(width 0.05)
				(type default)
			)
			(fill no)
			(layer "B.CrtYd")
		)
		(fp_rect
			(start -0.5 0.25)
			(end 0.5 -0.25)
			(stroke
				(width 0.15)
				(type solid)
			)
			(fill no)
			(layer "B.Fab")
		)
		(fp_text user "Author: Antmicro"
			(at -0.95 -4.169 90)
			(layer "B.Fab")
			(effects
				(font
					(size 0.7 0.7)
					(thickness 0.15)
				)
				(justify left bottom mirror)
			)
		)
		(fp_text user "License: Apache-2.0"
			(at -0.95 -5.169 90)
			(layer "B.Fab")
			(effects
				(font
					(size 0.7 0.7)
					(thickness 0.15)
				)
				(justify left bottom mirror)
			)
		)
		(fp_text user "${REFERENCE}"
			(at -0.95 -3.168 90)
			(layer "B.Fab")
			(effects
				(font
					(size 0.7 0.7)
					(thickness 0.15)
				)
				(justify left bottom mirror)
			)
		)
		(pad "1" smd roundrect
			(at -0.48 0 270)
			(size 0.59 0.64)
			(layers "B.Cu" "B.Mask" "B.Paste")
			(roundrect_rratio 0.25)
			(net 176 "Net-(J401-LED_GRN-)")
			(pintype "passive")
		)
		(pad "2" smd roundrect
			(at 0.48 0 270)
			(size 0.59 0.64)
			(layers "B.Cu" "B.Mask" "B.Paste")
			(roundrect_rratio 0.25)
			(net 214 "/Compute module/ETHERNET.LED_LINK")
			(pintype "passive")
		)
	)
	(footprint "antmicro-footprints:C_2220_5650Metric"
		(layer "B.Cu")
		(at 49.192962 145.6465 90)
		(descr "Capacitor SMD 2220")
		(tags "capacitor SMD 2220")
		(property "Reference" "C404"
			(at -4.52 -1.495 180)
			(layer "B.SilkS")
			(effects
				(font
					(size 0.7 0.7)
					(thickness 0.15)
				)
				(justify right bottom mirror)
			)
		)
		(property "Value" "C_22u_100V_2220"
			(at 0 -3.9 90)
			(layer "B.Fab")
			(effects
				(font
					(size 0.7 0.7)
					(thickness 0.15)
				)
				(justify right bottom mirror)
			)
		)
		(property "Datasheet" "https://product.tdk.com/en/search/capacitor/ceramic/mlcc/info?part_no=C5750X7S2A226M280KB"
			(at 0 0 90)
			(layer "B.Fab")
			(hide yes)
			(effects
				(font
					(size 1.27 1.27)
					(thickness 0.15)
				)
			)
		)
		(property "Manufacturer" "TDK"
			(at 0 0 90)
			(unlocked yes)
			(layer "B.Fab")
			(hide yes)
			(effects
				(font
					(size 1 1)
					(thickness 0.15)
				)
				(justify mirror)
			)
		)
		(property "MPN" "C5750X7S2A226M280KB"
			(at 0 0 90)
			(unlocked yes)
			(layer "B.Fab")
			(hide yes)
			(effects
				(font
					(size 1 1)
					(thickness 0.15)
				)
				(justify mirror)
			)
		)
		(property "Val" "22u"
			(at 0 0 90)
			(unlocked yes)
			(layer "B.Fab")
			(hide yes)
			(effects
				(font
					(size 1 1)
					(thickness 0.15)
				)
				(justify mirror)
			)
		)
		(property "License" "Apache-2.0"
			(at 0 0 90)
			(unlocked yes)
			(layer "B.Fab")
			(hide yes)
			(effects
				(font
					(size 1 1)
					(thickness 0.15)
				)
				(justify mirror)
			)
		)
		(property "Author" "Antmicro"
			(at 0 0 90)
			(unlocked yes)
			(layer "B.Fab")
			(hide yes)
			(effects
				(font
					(size 1 1)
					(thickness 0.15)
				)
				(justify mirror)
			)
		)
		(property "Voltage" "100V"
			(at 0 0 90)
			(unlocked yes)
			(layer "B.Fab")
			(hide yes)
			(effects
				(font
					(size 1 1)
					(thickness 0.15)
				)
				(justify mirror)
			)
		)
		(property "Dielectric" "X7S"
			(at 0 0 90)
			(unlocked yes)
			(layer "B.Fab")
			(hide yes)
			(effects
				(font
					(size 1 1)
					(thickness 0.15)
				)
				(justify mirror)
			)
		)
		(property "Public" "False"
			(at 0 0 90)
			(unlocked yes)
			(layer "B.Fab")
			(hide yes)
			(effects
				(font
					(size 1 1)
					(thickness 0.15)
				)
				(justify mirror)
			)
		)
		(sheetname "/Ethernet/")
		(sheetfile "ethernet.kicad_sch")
		(attr smd)
		(fp_line
			(start -1.415 -2.61)
			(end 1.415 -2.61)
			(stroke
				(width 0.15)
				(type solid)
			)
			(layer "B.SilkS")
		)
		(fp_line
			(start -1.415 2.61)
			(end 1.415 2.61)
			(stroke
				(width 0.15)
				(type solid)
			)
			(layer "B.SilkS")
		)
		(fp_rect
			(start -3.7 2.95)
			(end 3.7 -2.95)
			(stroke
				(width 0.05)
				(type solid)
			)
			(fill no)
			(layer "B.CrtYd")
		)
		(fp_rect
			(start -2.85 2.5)
			(end 2.85 -2.5)
			(stroke
				(width 0.15)
				(type solid)
			)
			(fill no)
			(layer "B.Fab")
		)
		(fp_text user "License: Apache-2.0"
			(at -3.7 -6.9 270)
			(layer "B.Fab")
			(effects
				(font
					(size 0.7 0.7)
					(thickness 0.15)
				)
				(justify left bottom mirror)
			)
		)
		(fp_text user "Author: Antmicro"
			(at -3.7 -7.9 270)
			(layer "B.Fab")
			(effects
				(font
					(size 0.7 0.7)
					(thickness 0.15)
				)
				(justify left bottom mirror)
			)
		)
		(fp_text user "${REFERENCE}"
			(at -3.7 -5.9 270)
			(layer "B.Fab")
			(effects
				(font
					(size 0.7 0.7)
					(thickness 0.15)
				)
				(justify left bottom mirror)
			)
		)
		(pad "1" smd roundrect
			(at -2.55 0 90)
			(size 1.8 5.4)
			(layers "B.Cu" "B.Mask" "B.Paste")
			(roundrect_rratio 0.138889)
			(net 1 "GNDD")
			(pintype "passive")
		)
		(pad "2" smd roundrect
			(at 2.55 0 90)
			(size 1.8 5.4)
			(layers "B.Cu" "B.Mask" "B.Paste")
			(roundrect_rratio 0.138889)
			(net 33 "/Ethernet/VDD")
			(pintype "passive")
		)
	)
	(footprint "antmicro-footprints:R_0402_1005Metric"
		(layer "B.Cu")
		(at 59.792962 165.4805)
		(descr "Resistor SMD 0402")
		(tags "resistor SMD 0402")
		(property "Reference" "R302"
			(at 0.507038 0.4195 315)
			(layer "B.SilkS")
			(effects
				(font
					(size 0.7 0.7)
					(thickness 0.15)
				)
				(justify right bottom mirror)
			)
		)
		(property "Value" "R_33k_0402"
			(at -1.011843 -1.772047 0)
			(layer "B.Fab")
			(effects
				(font
					(size 0.7 0.7)
					(thickness 0.15)
				)
				(justify right bottom mirror)
			)
		)
		(property "Datasheet" "https://www.bourns.com/docs/product-datasheets/cr.pdf"
			(at 0 0 0)
			(layer "B.Fab")
			(hide yes)
			(effects
				(font
					(size 1.27 1.27)
					(thickness 0.15)
				)
			)
		)
		(property "MPN" "CR0402-FX-3302GLF"
			(at 0 0 0)
			(unlocked yes)
			(layer "B.Fab")
			(hide yes)
			(effects
				(font
					(size 1 1)
					(thickness 0.15)
				)
				(justify mirror)
			)
		)
		(property "Manufacturer" "Bourns"
			(at 0 0 0)
			(unlocked yes)
			(layer "B.Fab")
			(hide yes)
			(effects
				(font
					(size 1 1)
					(thickness 0.15)
				)
				(justify mirror)
			)
		)
		(property "License" "Apache-2.0"
			(at 0 0 0)
			(unlocked yes)
			(layer "B.Fab")
			(hide yes)
			(effects
				(font
					(size 1 1)
					(thickness 0.15)
				)
				(justify mirror)
			)
		)
		(property "Author" "Antmicro"
			(at 0 0 0)
			(unlocked yes)
			(layer "B.Fab")
			(hide yes)
			(effects
				(font
					(size 1 1)
					(thickness 0.15)
				)
				(justify mirror)
			)
		)
		(property "Val" "33k"
			(at 0 0 0)
			(unlocked yes)
			(layer "B.Fab")
			(hide yes)
			(effects
				(font
					(size 1 1)
					(thickness 0.15)
				)
				(justify mirror)
			)
		)
		(property "Tolerance" "1%"
			(at 0 0 0)
			(unlocked yes)
			(layer "B.Fab")
			(hide yes)
			(effects
				(font
					(size 1 1)
					(thickness 0.15)
				)
				(justify mirror)
			)
		)
		(sheetname "/Supply/")
		(sheetfile "supply.kicad_sch")
		(attr smd)
		(fp_rect
			(start -0.925 0.47)
			(end 0.925 -0.47)
			(stroke
				(width 0.05)
				(type default)
			)
			(fill no)
			(layer "B.CrtYd")
		)
		(fp_rect
			(start -0.5 0.25)
			(end 0.5 -0.25)
			(stroke
				(width 0.15)
				(type solid)
			)
			(fill no)
			(layer "B.Fab")
		)
		(fp_text user "License: Apache-2.0"
			(at -0.95 -5.169 180)
			(layer "B.Fab")
			(effects
				(font
					(size 0.7 0.7)
					(thickness 0.15)
				)
				(justify left bottom mirror)
			)
		)
		(fp_text user "${REFERENCE}"
			(at -0.95 -3.168 180)
			(layer "B.Fab")
			(effects
				(font
					(size 0.7 0.7)
					(thickness 0.15)
				)
				(justify left bottom mirror)
			)
		)
		(fp_text user "Author: Antmicro"
			(at -0.95 -4.169 180)
			(layer "B.Fab")
			(effects
				(font
					(size 0.7 0.7)
					(thickness 0.15)
				)
				(justify left bottom mirror)
			)
		)
		(pad "1" smd roundrect
			(at -0.48 0)
			(size 0.59 0.64)
			(layers "B.Cu" "B.Mask" "B.Paste")
			(roundrect_rratio 0.25)
			(net 3 "GND")
			(pintype "passive")
		)
		(pad "2" smd roundrect
			(at 0.48 0)
			(size 0.59 0.64)
			(layers "B.Cu" "B.Mask" "B.Paste")
			(roundrect_rratio 0.25)
			(net 334 "Net-(Q302-REF)")
			(pintype "passive")
		)
	)
)
